(kicad_pcb
	(version 20260206)
	(generator "pcbnew")
	(generator_version "10.0")
	(general
		(thickness 1.6)
		(legacy_teardrops no)
	)
	(paper "A4")
	(title_block
		(title "03242023_DA0F0TMBIJ0_F0T_Motherboard_J_brd_V01_OCP.brd")
		(comment 1 "Grand Teton / footprints 4086-4090 of 6105")
	)
	(layers
		(0 "F.Cu" signal "TOP")
		(4 "In1.Cu" signal "GND")
		(6 "In2.Cu" signal "IN1")
		(8 "In3.Cu" signal "GND1")
		(10 "In4.Cu" signal "IN2")
		(12 "In5.Cu" signal "GND2")
		(14 "In6.Cu" signal "IN3")
		(16 "In7.Cu" signal "GND3")
		(18 "In8.Cu" signal "VCC")
		(20 "In9.Cu" signal "VCC1")
		(22 "In10.Cu" signal "GND4")
		(24 "In11.Cu" signal "IN4")
		(26 "In12.Cu" signal "GND5")
		(28 "In13.Cu" signal "IN5")
		(30 "In14.Cu" signal "GND6")
		(32 "In15.Cu" signal "IN6")
		(34 "In16.Cu" signal "GND7")
		(2 "B.Cu" signal "BOTTOM")
		(9 "F.Adhes" user "F.Adhesive")
		(11 "B.Adhes" user "B.Adhesive")
		(13 "F.Paste" user "Package Geometry/Pastemask Top")
		(15 "B.Paste" user "Package Geometry/Pastemask Bottom")
		(5 "F.SilkS" user "Ref Des/Silkscreen Top")
		(7 "B.SilkS" user "Ref Des/Silkscreen Bottom")
		(1 "F.Mask" user "Board Geometry/Soldermask Top")
		(3 "B.Mask" user "Board Geometry/Soldermask Bottom")
		(17 "Dwgs.User" user "User.Drawings")
		(19 "Cmts.User" user "User.Comments")
		(21 "Eco1.User" user "User.Eco1")
		(23 "Eco2.User" user "User.Eco2")
		(25 "Edge.Cuts" user "Board Geometry/Outline")
		(27 "Margin" user)
		(31 "F.CrtYd" user "Package Geometry/Place Bound Top")
		(29 "B.CrtYd" user "Package Geometry/Place Bound Bottom")
		(35 "F.Fab" user "Ref Des/Assembly Top")
		(33 "B.Fab" user "Ref Des/Assembly Bottom")
	)
	(footprint ""
		(layer "F.Cu")
		(at 20.906994 -180.682646 90)
		(property "Reference" "PC1282"
			(at 0 0 90)
			(layer "F.SilkS")
			(hide yes)
			(effects
				(font
					(size 1.27 1.27)
				)
			)
		)
		(property "Value" ""
			(at 0 0 90)
			(layer "F.Fab")
			(effects
				(font
					(size 1.27 1.27)
				)
			)
		)
		(duplicate_pad_numbers_are_jumpers no)
		(fp_line
			(start 0.7874 -0.4064)
			(end 0.7874 0.4064)
			(stroke
				(width 0.1524)
				(type default)
			)
			(layer "F.SilkS")
		)
		(fp_line
			(start -0.7874 -0.4064)
			(end 0.7874 -0.4064)
			(stroke
				(width 0.1524)
				(type default)
			)
			(layer "F.SilkS")
		)
		(fp_line
			(start 0.7874 0.4064)
			(end -0.7874 0.4064)
			(stroke
				(width 0.1524)
				(type default)
			)
			(layer "F.SilkS")
		)
		(fp_line
			(start -0.7874 0.4064)
			(end -0.7874 -0.4064)
			(stroke
				(width 0.1524)
				(type default)
			)
			(layer "F.SilkS")
		)
		(fp_line
			(start -0.12065 -0.305054)
			(end -0.12065 -0.2794)
			(stroke
				(width 0.1)
				(type default)
			)
			(layer "F.Fab")
		)
		(fp_line
			(start -0.67945 -0.305054)
			(end -0.12065 -0.305054)
			(stroke
				(width 0.1)
				(type default)
			)
			(layer "F.Fab")
		)
		(fp_line
			(start 0.67945 -0.3048)
			(end 0.67945 0.3048)
			(stroke
				(width 0.1)
				(type default)
			)
			(layer "F.Fab")
		)
		(fp_line
			(start 0.12065 -0.3048)
			(end 0.67945 -0.3048)
			(stroke
				(width 0.1)
				(type default)
			)
			(layer "F.Fab")
		)
		(fp_line
			(start 0.12065 -0.2794)
			(end 0.12065 -0.3048)
			(stroke
				(width 0.1)
				(type default)
			)
			(layer "F.Fab")
		)
		(fp_line
			(start -0.12065 -0.2794)
			(end 0.12065 -0.2794)
			(stroke
				(width 0.1)
				(type default)
			)
			(layer "F.Fab")
		)
		(fp_line
			(start 0.120396 0.2794)
			(end -0.12065 0.2794)
			(stroke
				(width 0.1)
				(type default)
			)
			(layer "F.Fab")
		)
		(fp_line
			(start -0.12065 0.2794)
			(end -0.12065 0.3048)
			(stroke
				(width 0.1)
				(type default)
			)
			(layer "F.Fab")
		)
		(fp_line
			(start 0.67945 0.3048)
			(end 0.120396 0.3048)
			(stroke
				(width 0.1)
				(type default)
			)
			(layer "F.Fab")
		)
		(fp_line
			(start 0.120396 0.3048)
			(end 0.120396 0.2794)
			(stroke
				(width 0.1)
				(type default)
			)
			(layer "F.Fab")
		)
		(fp_line
			(start -0.12065 0.3048)
			(end -0.67945 0.3048)
			(stroke
				(width 0.1)
				(type default)
			)
			(layer "F.Fab")
		)
		(fp_line
			(start -0.67945 0.3048)
			(end -0.67945 -0.305054)
			(stroke
				(width 0.1)
				(type default)
			)
			(layer "F.Fab")
		)
		(pad "1" smd circle
			(at -0.40005 0 90)
			(size 0 0)
			(layers "F.Cu" "F.Mask" "F.Paste")
			(net "SW_P12V_PVCCINFAON_CPU1_FLT")
		)
		(pad "2" smd circle
			(at 0.40005 0 90)
			(size 0 0)
			(layers "F.Cu" "F.Mask" "F.Paste")
			(net "GND")
		)
	)
	(footprint ""
		(layer "F.Cu")
		(at 109.580934 -395.17574)
		(property "Reference" "R3489"
			(at 0 0 0)
			(layer "F.SilkS")
			(hide yes)
			(effects
				(font
					(size 1.27 1.27)
				)
			)
		)
		(property "Value" ""
			(at 0 0 0)
			(layer "F.Fab")
			(effects
				(font
					(size 1.27 1.27)
				)
			)
		)
		(duplicate_pad_numbers_are_jumpers no)
		(fp_line
			(start -0.7874 -0.4064)
			(end 0.7874 -0.4064)
			(stroke
				(width 0.1524)
				(type default)
			)
			(layer "F.SilkS")
		)
		(fp_line
			(start -0.7874 0.4064)
			(end -0.7874 -0.4064)
			(stroke
				(width 0.1524)
				(type default)
			)
			(layer "F.SilkS")
		)
		(fp_line
			(start 0.7874 -0.4064)
			(end 0.7874 0.4064)
			(stroke
				(width 0.1524)
				(type default)
			)
			(layer "F.SilkS")
		)
		(fp_line
			(start 0.7874 0.4064)
			(end -0.7874 0.4064)
			(stroke
				(width 0.1524)
				(type default)
			)
			(layer "F.SilkS")
		)
		(fp_line
			(start -0.67945 -0.305054)
			(end -0.12065 -0.305054)
			(stroke
				(width 0.1)
				(type default)
			)
			(layer "F.Fab")
		)
		(fp_line
			(start -0.67945 0.3048)
			(end -0.67945 -0.305054)
			(stroke
				(width 0.1)
				(type default)
			)
			(layer "F.Fab")
		)
		(fp_line
			(start -0.12065 -0.305054)
			(end -0.12065 -0.2794)
			(stroke
				(width 0.1)
				(type default)
			)
			(layer "F.Fab")
		)
		(fp_line
			(start -0.12065 -0.2794)
			(end 0.12065 -0.2794)
			(stroke
				(width 0.1)
				(type default)
			)
			(layer "F.Fab")
		)
		(fp_line
			(start -0.12065 0.2794)
			(end -0.12065 0.3048)
			(stroke
				(width 0.1)
				(type default)
			)
			(layer "F.Fab")
		)
		(fp_line
			(start -0.12065 0.3048)
			(end -0.67945 0.3048)
			(stroke
				(width 0.1)
				(type default)
			)
			(layer "F.Fab")
		)
		(fp_line
			(start 0.120396 0.2794)
			(end -0.12065 0.2794)
			(stroke
				(width 0.1)
				(type default)
			)
			(layer "F.Fab")
		)
		(fp_line
			(start 0.120396 0.3048)
			(end 0.120396 0.2794)
			(stroke
				(width 0.1)
				(type default)
			)
			(layer "F.Fab")
		)
		(fp_line
			(start 0.12065 -0.3048)
			(end 0.67945 -0.3048)
			(stroke
				(width 0.1)
				(type default)
			)
			(layer "F.Fab")
		)
		(fp_line
			(start 0.12065 -0.2794)
			(end 0.12065 -0.3048)
			(stroke
				(width 0.1)
				(type default)
			)
			(layer "F.Fab")
		)
		(fp_line
			(start 0.67945 -0.3048)
			(end 0.67945 0.3048)
			(stroke
				(width 0.1)
				(type default)
			)
			(layer "F.Fab")
		)
		(fp_line
			(start 0.67945 0.3048)
			(end 0.120396 0.3048)
			(stroke
				(width 0.1)
				(type default)
			)
			(layer "F.Fab")
		)
		(pad "1" smd circle
			(at -0.40005 0)
			(size 0 0)
			(layers "F.Cu" "F.Mask" "F.Paste")
			(net "GPU_FPGA_EROT_RST_N")
		)
		(pad "2" smd circle
			(at 0.40005 0)
			(size 0 0)
			(layers "F.Cu" "F.Mask" "F.Paste")
			(net "GND")
		)
	)
	(footprint ""
		(layer "F.Cu")
		(at 341.133176 -339.51545 -90)
		(property "Reference" "PC252_P0_6"
			(at 0 0 270)
			(layer "F.SilkS")
			(hide yes)
			(effects
				(font
					(size 1.27 1.27)
				)
			)
		)
		(property "Value" ""
			(at 0 0 270)
			(layer "F.Fab")
			(effects
				(font
					(size 1.27 1.27)
				)
			)
		)
		(duplicate_pad_numbers_are_jumpers no)
		(fp_line
			(start -0.7874 0.4064)
			(end -0.7874 -0.4064)
			(stroke
				(width 0.1524)
				(type default)
			)
			(layer "F.SilkS")
		)
		(fp_line
			(start 0.7874 0.4064)
			(end -0.7874 0.4064)
			(stroke
				(width 0.1524)
				(type default)
			)
			(layer "F.SilkS")
		)
		(fp_line
			(start -0.7874 -0.4064)
			(end 0.7874 -0.4064)
			(stroke
				(width 0.1524)
				(type default)
			)
			(layer "F.SilkS")
		)
		(fp_line
			(start 0.7874 -0.4064)
			(end 0.7874 0.4064)
			(stroke
				(width 0.1524)
				(type default)
			)
			(layer "F.SilkS")
		)
		(fp_line
			(start -0.67945 0.3048)
			(end -0.67945 -0.305054)
			(stroke
				(width 0.1)
				(type default)
			)
			(layer "F.Fab")
		)
		(fp_line
			(start -0.12065 0.3048)
			(end -0.67945 0.3048)
			(stroke
				(width 0.1)
				(type default)
			)
			(layer "F.Fab")
		)
		(fp_line
			(start 0.120396 0.3048)
			(end 0.120396 0.2794)
			(stroke
				(width 0.1)
				(type default)
			)
			(layer "F.Fab")
		)
		(fp_line
			(start 0.67945 0.3048)
			(end 0.120396 0.3048)
			(stroke
				(width 0.1)
				(type default)
			)
			(layer "F.Fab")
		)
		(fp_line
			(start -0.12065 0.2794)
			(end -0.12065 0.3048)
			(stroke
				(width 0.1)
				(type default)
			)
			(layer "F.Fab")
		)
		(fp_line
			(start 0.120396 0.2794)
			(end -0.12065 0.2794)
			(stroke
				(width 0.1)
				(type default)
			)
			(layer "F.Fab")
		)
		(fp_line
			(start -0.12065 -0.2794)
			(end 0.12065 -0.2794)
			(stroke
				(width 0.1)
				(type default)
			)
			(layer "F.Fab")
		)
		(fp_line
			(start 0.12065 -0.2794)
			(end 0.12065 -0.3048)
			(stroke
				(width 0.1)
				(type default)
			)
			(layer "F.Fab")
		)
		(fp_line
			(start 0.12065 -0.3048)
			(end 0.67945 -0.3048)
			(stroke
				(width 0.1)
				(type default)
			)
			(layer "F.Fab")
		)
		(fp_line
			(start 0.67945 -0.3048)
			(end 0.67945 0.3048)
			(stroke
				(width 0.1)
				(type default)
			)
			(layer "F.Fab")
		)
		(fp_line
			(start -0.67945 -0.305054)
			(end -0.12065 -0.305054)
			(stroke
				(width 0.1)
				(type default)
			)
			(layer "F.Fab")
		)
		(fp_line
			(start -0.12065 -0.305054)
			(end -0.12065 -0.2794)
			(stroke
				(width 0.1)
				(type default)
			)
			(layer "F.Fab")
		)
		(pad "1" smd circle
			(at -0.40005 0 270)
			(size 0 0)
			(layers "F.Cu" "F.Mask" "F.Paste")
			(net "SW_P12V_PVCCIN_CPU0_FLT")
		)
		(pad "2" smd circle
			(at 0.40005 0 270)
			(size 0 0)
			(layers "F.Cu" "F.Mask" "F.Paste")
			(net "GND")
		)
	)
	(footprint ""
		(layer "F.Cu")
		(at 288.9377 -405.79802 180)
		(property "Reference" "R4686"
			(at 0 0 180)
			(layer "F.SilkS")
			(hide yes)
			(effects
				(font
					(size 1.27 1.27)
				)
			)
		)
		(property "Value" ""
			(at 0 0 180)
			(layer "F.Fab")
			(effects
				(font
					(size 1.27 1.27)
				)
			)
		)
		(duplicate_pad_numbers_are_jumpers no)
		(fp_line
			(start 0.7874 0.4064)
			(end -0.7874 0.4064)
			(stroke
				(width 0.1524)
				(type default)
			)
			(layer "F.SilkS")
		)
		(fp_line
			(start 0.7874 -0.4064)
			(end 0.7874 0.4064)
			(stroke
				(width 0.1524)
				(type default)
			)
			(layer "F.SilkS")
		)
		(fp_line
			(start -0.7874 0.4064)
			(end -0.7874 -0.4064)
			(stroke
				(width 0.1524)
				(type default)
			)
			(layer "F.SilkS")
		)
		(fp_line
			(start -0.7874 -0.4064)
			(end 0.7874 -0.4064)
			(stroke
				(width 0.1524)
				(type default)
			)
			(layer "F.SilkS")
		)
		(fp_line
			(start 0.67945 0.3048)
			(end 0.120396 0.3048)
			(stroke
				(width 0.1)
				(type default)
			)
			(layer "F.Fab")
		)
		(fp_line
			(start 0.67945 -0.3048)
			(end 0.67945 0.3048)
			(stroke
				(width 0.1)
				(type default)
			)
			(layer "F.Fab")
		)
		(fp_line
			(start 0.12065 -0.2794)
			(end 0.12065 -0.3048)
			(stroke
				(width 0.1)
				(type default)
			)
			(layer "F.Fab")
		)
		(fp_line
			(start 0.12065 -0.3048)
			(end 0.67945 -0.3048)
			(stroke
				(width 0.1)
				(type default)
			)
			(layer "F.Fab")
		)
		(fp_line
			(start 0.120396 0.3048)
			(end 0.120396 0.2794)
			(stroke
				(width 0.1)
				(type default)
			)
			(layer "F.Fab")
		)
		(fp_line
			(start 0.120396 0.2794)
			(end -0.12065 0.2794)
			(stroke
				(width 0.1)
				(type default)
			)
			(layer "F.Fab")
		)
		(fp_line
			(start -0.12065 0.3048)
			(end -0.67945 0.3048)
			(stroke
				(width 0.1)
				(type default)
			)
			(layer "F.Fab")
		)
		(fp_line
			(start -0.12065 0.2794)
			(end -0.12065 0.3048)
			(stroke
				(width 0.1)
				(type default)
			)
			(layer "F.Fab")
		)
		(fp_line
			(start -0.12065 -0.2794)
			(end 0.12065 -0.2794)
			(stroke
				(width 0.1)
				(type default)
			)
			(layer "F.Fab")
		)
		(fp_line
			(start -0.12065 -0.305054)
			(end -0.12065 -0.2794)
			(stroke
				(width 0.1)
				(type default)
			)
			(layer "F.Fab")
		)
		(fp_line
			(start -0.67945 0.3048)
			(end -0.67945 -0.305054)
			(stroke
				(width 0.1)
				(type default)
			)
			(layer "F.Fab")
		)
		(fp_line
			(start -0.67945 -0.305054)
			(end -0.12065 -0.305054)
			(stroke
				(width 0.1)
				(type default)
			)
			(layer "F.Fab")
		)
		(pad "1" smd circle
			(at -0.40005 0 180)
			(size 0 0)
			(layers "F.Cu" "F.Mask" "F.Paste")
			(net "P3V3_AUX")
		)
		(pad "2" smd circle
			(at 0.40005 0 180)
			(size 0 0)
			(layers "F.Cu" "F.Mask" "F.Paste")
			(net "P12V_HSC_T_CRIT_R_N")
		)
	)
	(footprint ""
		(layer "F.Cu")
		(at 164.465 -99.786948)
		(property "Reference" "R1758"
			(at 0 0 0)
			(layer "F.SilkS")
			(hide yes)
			(effects
				(font
					(size 1.27 1.27)
				)
			)
		)
		(property "Value" ""
			(at 0 0 0)
			(layer "F.Fab")
			(effects
				(font
					(size 1.27 1.27)
				)
			)
		)
		(duplicate_pad_numbers_are_jumpers no)
		(fp_line
			(start -0.7874 -0.4064)
			(end 0.7874 -0.4064)
			(stroke
				(width 0.1524)
				(type default)
			)
			(layer "F.SilkS")
		)
		(fp_line
			(start -0.7874 0.4064)
			(end -0.7874 -0.4064)
			(stroke
				(width 0.1524)
				(type default)
			)
			(layer "F.SilkS")
		)
		(fp_line
			(start 0.7874 -0.4064)
			(end 0.7874 0.4064)
			(stroke
				(width 0.1524)
				(type default)
			)
			(layer "F.SilkS")
		)
		(fp_line
			(start 0.7874 0.4064)
			(end -0.7874 0.4064)
			(stroke
				(width 0.1524)
				(type default)
			)
			(layer "F.SilkS")
		)
		(fp_line
			(start -0.67945 -0.305054)
			(end -0.12065 -0.305054)
			(stroke
				(width 0.1)
				(type default)
			)
			(layer "F.Fab")
		)
		(fp_line
			(start -0.67945 0.3048)
			(end -0.67945 -0.305054)
			(stroke
				(width 0.1)
				(type default)
			)
			(layer "F.Fab")
		)
		(fp_line
			(start -0.12065 -0.305054)
			(end -0.12065 -0.2794)
			(stroke
				(width 0.1)
				(type default)
			)
			(layer "F.Fab")
		)
		(fp_line
			(start -0.12065 -0.2794)
			(end 0.12065 -0.2794)
			(stroke
				(width 0.1)
				(type default)
			)
			(layer "F.Fab")
		)
		(fp_line
			(start -0.12065 0.2794)
			(end -0.12065 0.3048)
			(stroke
				(width 0.1)
				(type default)
			)
			(layer "F.Fab")
		)
		(fp_line
			(start -0.12065 0.3048)
			(end -0.67945 0.3048)
			(stroke
				(width 0.1)
				(type default)
			)
			(layer "F.Fab")
		)
		(fp_line
			(start 0.120396 0.2794)
			(end -0.12065 0.2794)
			(stroke
				(width 0.1)
				(type default)
			)
			(layer "F.Fab")
		)
		(fp_line
			(start 0.120396 0.3048)
			(end 0.120396 0.2794)
			(stroke
				(width 0.1)
				(type default)
			)
			(layer "F.Fab")
		)
		(fp_line
			(start 0.12065 -0.3048)
			(end 0.67945 -0.3048)
			(stroke
				(width 0.1)
				(type default)
			)
			(layer "F.Fab")
		)
		(fp_line
			(start 0.12065 -0.2794)
			(end 0.12065 -0.3048)
			(stroke
				(width 0.1)
				(type default)
			)
			(layer "F.Fab")
		)
		(fp_line
			(start 0.67945 -0.3048)
			(end 0.67945 0.3048)
			(stroke
				(width 0.1)
				(type default)
			)
			(layer "F.Fab")
		)
		(fp_line
			(start 0.67945 0.3048)
			(end 0.120396 0.3048)
			(stroke
				(width 0.1)
				(type default)
			)
			(layer "F.Fab")
		)
		(pad "1" smd circle
			(at -0.40005 0)
			(size 0 0)
			(layers "F.Cu" "F.Mask" "F.Paste")
			(net "SGPIO_LD_1")
		)
		(pad "2" smd circle
			(at 0.40005 0)
			(size 0 0)
			(layers "F.Cu" "F.Mask" "F.Paste")
			(net "SGPIO_BMC_LD_N")
		)
	)
)
